(kicad_pcb
	(version 20260206)
	(generator "pcbnew")
	(generator_version "10.0")
	(general
		(thickness 1.6)
		(legacy_teardrops no)
	)
	(paper "A4")
	(title_block
		(title "peb — Lightning_PEB_BRD.brd")
		(comment 1 "Lightning (Wiwynn / Facebook NVMe JBOF) / footprints 2458-2467 of 2563")
	)
	(layers
		(0 "F.Cu" signal "TOP")
		(4 "In1.Cu" signal "L2GND")
		(6 "In2.Cu" signal "L3")
		(8 "In3.Cu" signal "L4VCC")
		(10 "In4.Cu" signal "L5VCC")
		(12 "In5.Cu" signal "L6")
		(14 "In6.Cu" signal "L7GND")
		(2 "B.Cu" signal "BOTTOM")
		(9 "F.Adhes" user "F.Adhesive")
		(11 "B.Adhes" user "B.Adhesive")
		(13 "F.Paste" user "Package Geometry/Pastemask Top")
		(15 "B.Paste" user "Package Geometry/Pastemask Bottom")
		(5 "F.SilkS" user "Ref Des/Silkscreen Top")
		(7 "B.SilkS" user "Ref Des/Silkscreen Bottom")
		(1 "F.Mask" user "Board Geometry/Soldermask Top")
		(3 "B.Mask" user "Board Geometry/Soldermask Bottom")
		(17 "Dwgs.User" user "User.Drawings")
		(19 "Cmts.User" user "User.Comments")
		(21 "Eco1.User" user "User.Eco1")
		(23 "Eco2.User" user "User.Eco2")
		(25 "Edge.Cuts" user "Board Geometry/Outline")
		(27 "Margin" user)
		(31 "F.CrtYd" user "Package Geometry/Place Bound Top")
		(29 "B.CrtYd" user "Package Geometry/Place Bound Bottom")
		(35 "F.Fab" user "Ref Des/Assembly Top")
		(33 "B.Fab" user "Ref Des/Assembly Bottom")
	)
	(footprint ""
		(layer "B.Cu")
		(at 125.960124 -196.443092)
		(property "Reference" "R4129"
			(at 0 0 0)
			(layer "B.SilkS")
			(hide yes)
			(effects
				(font
					(size 1.27 1.27)
				)
				(justify mirror)
			)
		)
		(property "Value" "4K7R2F-GP"
			(at -0.064008 -3.993896 0)
			(unlocked yes)
			(layer "B.Fab")
			(hide yes)
			(effects
				(font
					(size 1.016 1.016)
					(thickness 0.1524)
				)
				(justify mirror)
			)
		)
		(property "Device Type" "R402H16"
			(at -0.064008 -5.517896 0)
			(unlocked yes)
			(layer "B.Fab")
			(hide yes)
			(effects
				(font
					(size 1.016 1.016)
					(thickness 0.1524)
				)
				(justify mirror)
			)
		)
		(duplicate_pad_numbers_are_jumpers no)
		(fp_line
			(start -0.508 -0.9398)
			(end 0.508 -0.9398)
			(stroke
				(width 0.1524)
				(type default)
			)
			(layer "B.SilkS")
		)
		(fp_line
			(start 0.508 -0.9398)
			(end 0.508 0.9398)
			(stroke
				(width 0.1524)
				(type default)
			)
			(layer "B.SilkS")
		)
		(fp_rect
			(start 0.508 0.9398)
			(end -0.508 -0.9398)
			(stroke
				(width 0)
				(type default)
			)
			(fill no)
			(layer "B.CrtYd")
		)
		(fp_rect
			(start 0.508 0.9398)
			(end -0.508 -0.9398)
			(stroke
				(width 0)
				(type default)
			)
			(fill no)
			(layer "B.Fab")
		)
		(pad "1" smd custom
			(at 0 -0.4445 180)
			(size 0.1397 0.1397)
			(layers "B.Cu" "B.Mask" "B.Paste")
			(net "SSD_PRSNT#1")
			(options
				(clearance outline)
				(anchor circle)
			)
			(primitives
				(gr_poly
					(pts
						(arc
							(start -0.1778 0.2794)
							(mid -0.249642 0.249642)
							(end -0.2794 0.1778)
						)
						(arc
							(start -0.2794 -0.1778)
							(mid -0.249642 -0.249642)
							(end -0.1778 -0.2794)
						)
						(arc
							(start 0.1778 -0.2794)
							(mid 0.249642 -0.249642)
							(end 0.2794 -0.1778)
						)
						(arc
							(start 0.2794 0.1778)
							(mid 0.249642 0.249642)
							(end 0.1778 0.2794)
						)
					)
					(width 0)
					(fill yes)
				)
			)
		)
		(pad "2" smd custom
			(at 0 0.4445 180)
			(size 0.1397 0.1397)
			(layers "B.Cu" "B.Mask" "B.Paste")
			(net "P3V3_STBY")
			(options
				(clearance outline)
				(anchor circle)
			)
			(primitives
				(gr_poly
					(pts
						(arc
							(start -0.1778 0.2794)
							(mid -0.249642 0.249642)
							(end -0.2794 0.1778)
						)
						(arc
							(start -0.2794 -0.1778)
							(mid -0.249642 -0.249642)
							(end -0.1778 -0.2794)
						)
						(arc
							(start 0.1778 -0.2794)
							(mid 0.249642 -0.249642)
							(end 0.2794 -0.1778)
						)
						(arc
							(start 0.2794 0.1778)
							(mid 0.249642 0.249642)
							(end 0.1778 0.2794)
						)
					)
					(width 0)
					(fill yes)
				)
			)
		)
	)
	(footprint ""
		(layer "B.Cu")
		(at 27.94 -73.533 180)
		(property "Reference" "PR66"
			(at 0 0 0)
			(layer "B.SilkS")
			(hide yes)
			(effects
				(font
					(size 1.27 1.27)
				)
				(justify mirror)
			)
		)
		(property "Value" "10KR2F-2-GP"
			(at -0.064008 -3.993896 180)
			(unlocked yes)
			(layer "B.Fab")
			(hide yes)
			(effects
				(font
					(size 1.016 1.016)
					(thickness 0.1524)
				)
				(justify mirror)
			)
		)
		(property "Device Type" "R402H16"
			(at -0.064008 -5.517896 180)
			(unlocked yes)
			(layer "B.Fab")
			(hide yes)
			(effects
				(font
					(size 1.016 1.016)
					(thickness 0.1524)
				)
				(justify mirror)
			)
		)
		(duplicate_pad_numbers_are_jumpers no)
		(fp_line
			(start 0.508 -0.9398)
			(end 0.508 0.9398)
			(stroke
				(width 0.1524)
				(type default)
			)
			(layer "B.SilkS")
		)
		(fp_line
			(start -0.508 -0.9398)
			(end 0.508 -0.9398)
			(stroke
				(width 0.1524)
				(type default)
			)
			(layer "B.SilkS")
		)
		(fp_rect
			(start 0.508 0.9398)
			(end -0.508 -0.9398)
			(stroke
				(width 0)
				(type default)
			)
			(fill no)
			(layer "B.CrtYd")
		)
		(fp_rect
			(start 0.508 0.9398)
			(end -0.508 -0.9398)
			(stroke
				(width 0)
				(type default)
			)
			(fill no)
			(layer "B.Fab")
		)
		(pad "1" smd custom
			(at 0 -0.4445)
			(size 0.1397 0.1397)
			(layers "B.Cu" "B.Mask" "B.Paste")
			(net "P5V_STBY_EN")
			(options
				(clearance outline)
				(anchor circle)
			)
			(primitives
				(gr_poly
					(pts
						(arc
							(start -0.1778 0.2794)
							(mid -0.249642 0.249642)
							(end -0.2794 0.1778)
						)
						(arc
							(start -0.2794 -0.1778)
							(mid -0.249642 -0.249642)
							(end -0.1778 -0.2794)
						)
						(arc
							(start 0.1778 -0.2794)
							(mid 0.249642 -0.249642)
							(end 0.2794 -0.1778)
						)
						(arc
							(start 0.2794 0.1778)
							(mid 0.249642 0.249642)
							(end 0.1778 0.2794)
						)
					)
					(width 0)
					(fill yes)
				)
			)
		)
		(pad "2" smd custom
			(at 0 0.4445)
			(size 0.1397 0.1397)
			(layers "B.Cu" "B.Mask" "B.Paste")
			(net "GND")
			(options
				(clearance outline)
				(anchor circle)
			)
			(primitives
				(gr_poly
					(pts
						(arc
							(start -0.1778 0.2794)
							(mid -0.249642 0.249642)
							(end -0.2794 0.1778)
						)
						(arc
							(start -0.2794 -0.1778)
							(mid -0.249642 -0.249642)
							(end -0.1778 -0.2794)
						)
						(arc
							(start 0.1778 -0.2794)
							(mid 0.249642 -0.249642)
							(end 0.2794 -0.1778)
						)
						(arc
							(start 0.2794 0.1778)
							(mid 0.249642 0.249642)
							(end 0.1778 0.2794)
						)
					)
					(width 0)
					(fill yes)
				)
			)
		)
	)
	(footprint ""
		(layer "B.Cu")
		(at 34.163 -118.364)
		(property "Reference" "TP226"
			(at 0 0 0)
			(layer "B.SilkS")
			(hide yes)
			(effects
				(font
					(size 1.27 1.27)
				)
				(justify mirror)
			)
		)
		(property "Value" "TPAD28-2-GP"
			(at 0.0127 -1.6637 0)
			(unlocked yes)
			(layer "B.Fab")
			(hide yes)
			(effects
				(font
					(size 1.016 1.016)
					(thickness 0.1524)
				)
				(justify mirror)
			)
		)
		(property "Device Type" "TPAD28"
			(at 0.0127 -3.1877 0)
			(unlocked yes)
			(layer "B.Fab")
			(hide yes)
			(effects
				(font
					(size 1.016 1.016)
					(thickness 0.1524)
				)
				(justify mirror)
			)
		)
		(duplicate_pad_numbers_are_jumpers no)
		(fp_poly
			(pts
				(arc
					(start 0.3556 0)
					(mid -0.3556 0)
					(end 0.3556 0)
				)
			)
			(stroke
				(width 0)
				(type default)
			)
			(fill no)
			(layer "B.CrtYd")
		)
		(fp_poly
			(pts
				(arc
					(start 0.6096 0)
					(mid -0.6096 0)
					(end 0.6096 0)
				)
			)
			(stroke
				(width 0)
				(type default)
			)
			(fill no)
			(layer "B.Fab")
		)
		(pad "1" smd circle
			(at 0 0 180)
			(size 0.7112 0.7112)
			(layers "B.Cu" "B.Mask" "B.Paste")
			(net "TP_GPIOE1")
		)
	)
	(footprint ""
		(layer "B.Cu")
		(at 8.9154 -68.2752 -90)
		(property "Reference" "C423"
			(at 0 0 90)
			(layer "B.SilkS")
			(hide yes)
			(effects
				(font
					(size 1.27 1.27)
				)
				(justify mirror)
			)
		)
		(property "Value" "SC47U4V5MX-2-GP"
			(at 0.0762 -6.1214 270)
			(unlocked yes)
			(layer "B.Fab")
			(hide yes)
			(effects
				(font
					(size 1.016 1.016)
					(thickness 0.1524)
				)
				(justify mirror)
			)
		)
		(property "Device Type" "C805H58"
			(at 0.0762 -8.1534 270)
			(unlocked yes)
			(layer "B.Fab")
			(hide yes)
			(effects
				(font
					(size 1.016 1.016)
					(thickness 0.1524)
				)
				(justify mirror)
			)
		)
		(duplicate_pad_numbers_are_jumpers no)
		(fp_line
			(start -0.635 0)
			(end 0.635 0)
			(stroke
				(width 0.508)
				(type default)
			)
			(layer "B.SilkS")
		)
		(fp_rect
			(start 0.9652 1.778)
			(end -0.9652 -1.778)
			(stroke
				(width 0)
				(type default)
			)
			(fill no)
			(layer "B.CrtYd")
		)
		(fp_poly
			(pts
				(xy 0.9652 -1.778) (xy -0.9652 -1.778) (xy -0.9652 1.778) (xy 0.9652 1.778)
			)
			(stroke
				(width 0)
				(type default)
			)
			(fill no)
			(layer "B.Fab")
		)
		(pad "1" smd rect
			(at 0 -0.9652 90)
			(size 1.397 1.143)
			(layers "B.Cu" "B.Mask" "B.Paste")
			(net "P1V5_I210")
		)
		(pad "2" smd rect
			(at 0 0.9652 90)
			(size 1.397 1.143)
			(layers "B.Cu" "B.Mask" "B.Paste")
			(net "GND")
		)
	)
	(footprint ""
		(layer "B.Cu")
		(at 247.5992 -60.071)
		(property "Reference" "C602"
			(at 0 0 0)
			(layer "B.SilkS")
			(hide yes)
			(effects
				(font
					(size 1.27 1.27)
				)
				(justify mirror)
			)
		)
		(property "Value" "SCD1U16V1KX-1-GP"
			(at 2.8321 -1.7399 0)
			(unlocked yes)
			(layer "B.Fab")
			(hide yes)
			(effects
				(font
					(size 1.016 1.016)
					(thickness 0.1524)
				)
				(justify mirror)
			)
		)
		(property "Device Type" "C0201H13"
			(at 2.8321 -3.2639 0)
			(unlocked yes)
			(layer "B.Fab")
			(hide yes)
			(effects
				(font
					(size 1.016 1.016)
					(thickness 0.1524)
				)
				(justify mirror)
			)
		)
		(duplicate_pad_numbers_are_jumpers no)
		(fp_rect
			(start 0.2794 0.6477)
			(end -0.2794 -0.6477)
			(stroke
				(width 0)
				(type default)
			)
			(fill no)
			(layer "B.CrtYd")
		)
		(fp_rect
			(start 0.2794 0.6477)
			(end -0.2794 -0.6477)
			(stroke
				(width 0)
				(type default)
			)
			(fill no)
			(layer "B.Fab")
		)
		(pad "1" smd custom
			(at 0 -0.2794 180)
			(size 0.0762 0.0762)
			(layers "B.Cu" "B.Mask" "B.Paste")
			(net "DUT_AVD_PCIE")
			(options
				(clearance outline)
				(anchor circle)
			)
			(primitives
				(gr_poly
					(pts
						(arc
							(start 0.1524 0.127)
							(mid 0.137521 0.162921)
							(end 0.1016 0.1778)
						)
						(arc
							(start -0.1016 0.1778)
							(mid -0.137521 0.162921)
							(end -0.1524 0.127)
						)
						(arc
							(start -0.1524 -0.127)
							(mid -0.137521 -0.162921)
							(end -0.1016 -0.1778)
						)
						(arc
							(start 0.1016 -0.1778)
							(mid 0.137521 -0.162921)
							(end 0.1524 -0.127)
						)
					)
					(width 0)
					(fill yes)
				)
			)
		)
		(pad "2" smd custom
			(at 0 0.2794 180)
			(size 0.0762 0.0762)
			(layers "B.Cu" "B.Mask" "B.Paste")
			(net "GND")
			(options
				(clearance outline)
				(anchor circle)
			)
			(primitives
				(gr_poly
					(pts
						(arc
							(start 0.1524 0.127)
							(mid 0.137521 0.162921)
							(end 0.1016 0.1778)
						)
						(arc
							(start -0.1016 0.1778)
							(mid -0.137521 0.162921)
							(end -0.1524 0.127)
						)
						(arc
							(start -0.1524 -0.127)
							(mid -0.137521 -0.162921)
							(end -0.1016 -0.1778)
						)
						(arc
							(start 0.1016 -0.1778)
							(mid 0.137521 -0.162921)
							(end 0.1524 -0.127)
						)
					)
					(width 0)
					(fill yes)
				)
			)
		)
	)
	(footprint ""
		(layer "B.Cu")
		(at 146.930618 -33.53562)
		(property "Reference" "R2928"
			(at 0 0 0)
			(layer "B.SilkS")
			(hide yes)
			(effects
				(font
					(size 1.27 1.27)
				)
				(justify mirror)
			)
		)
		(property "Value" "0R2J-2-GP"
			(at -0.064008 -3.993896 0)
			(unlocked yes)
			(layer "B.Fab")
			(hide yes)
			(effects
				(font
					(size 1.016 1.016)
					(thickness 0.1524)
				)
				(justify mirror)
			)
		)
		(property "Device Type" "R402H16"
			(at -0.064008 -5.517896 0)
			(unlocked yes)
			(layer "B.Fab")
			(hide yes)
			(effects
				(font
					(size 1.016 1.016)
					(thickness 0.1524)
				)
				(justify mirror)
			)
		)
		(duplicate_pad_numbers_are_jumpers no)
		(fp_line
			(start -0.508 -0.9398)
			(end 0.508 -0.9398)
			(stroke
				(width 0.1524)
				(type default)
			)
			(layer "B.SilkS")
		)
		(fp_line
			(start 0.508 -0.9398)
			(end 0.508 0.9398)
			(stroke
				(width 0.1524)
				(type default)
			)
			(layer "B.SilkS")
		)
		(fp_rect
			(start 0.508 0.9398)
			(end -0.508 -0.9398)
			(stroke
				(width 0)
				(type default)
			)
			(fill no)
			(layer "B.CrtYd")
		)
		(fp_rect
			(start 0.508 0.9398)
			(end -0.508 -0.9398)
			(stroke
				(width 0)
				(type default)
			)
			(fill no)
			(layer "B.Fab")
		)
		(pad "1" smd custom
			(at 0 -0.4445 180)
			(size 0.1397 0.1397)
			(layers "B.Cu" "B.Mask" "B.Paste")
			(net "BMC_I2C2_MINI2_SDA")
			(options
				(clearance outline)
				(anchor circle)
			)
			(primitives
				(gr_poly
					(pts
						(arc
							(start -0.1778 0.2794)
							(mid -0.249642 0.249642)
							(end -0.2794 0.1778)
						)
						(arc
							(start -0.2794 -0.1778)
							(mid -0.249642 -0.249642)
							(end -0.1778 -0.2794)
						)
						(arc
							(start 0.1778 -0.2794)
							(mid 0.249642 -0.249642)
							(end 0.2794 -0.1778)
						)
						(arc
							(start 0.2794 0.1778)
							(mid 0.249642 0.249642)
							(end 0.1778 0.2794)
						)
					)
					(width 0)
					(fill yes)
				)
			)
		)
		(pad "2" smd custom
			(at 0 0.4445 180)
			(size 0.1397 0.1397)
			(layers "B.Cu" "B.Mask" "B.Paste")
			(net "8644_CBL_PRSNT_R_2")
			(options
				(clearance outline)
				(anchor circle)
			)
			(primitives
				(gr_poly
					(pts
						(arc
							(start -0.1778 0.2794)
							(mid -0.249642 0.249642)
							(end -0.2794 0.1778)
						)
						(arc
							(start -0.2794 -0.1778)
							(mid -0.249642 -0.249642)
							(end -0.1778 -0.2794)
						)
						(arc
							(start 0.1778 -0.2794)
							(mid 0.249642 -0.249642)
							(end 0.2794 -0.1778)
						)
						(arc
							(start 0.2794 0.1778)
							(mid 0.249642 0.249642)
							(end 0.1778 0.2794)
						)
					)
					(width 0)
					(fill yes)
				)
			)
		)
	)
	(footprint ""
		(layer "B.Cu")
		(at 229.599998 -36.999164 -90)
		(property "Reference" "TP124"
			(at 0 0 90)
			(layer "B.SilkS")
			(hide yes)
			(effects
				(font
					(size 1.27 1.27)
				)
				(justify mirror)
			)
		)
		(property "Value" "TPAD28-2-GP"
			(at 0.0127 -1.6637 270)
			(unlocked yes)
			(layer "B.Fab")
			(hide yes)
			(effects
				(font
					(size 1.016 1.016)
					(thickness 0.1524)
				)
				(justify mirror)
			)
		)
		(property "Device Type" "TPAD28"
			(at 0.0127 -3.1877 270)
			(unlocked yes)
			(layer "B.Fab")
			(hide yes)
			(effects
				(font
					(size 1.016 1.016)
					(thickness 0.1524)
				)
				(justify mirror)
			)
		)
		(duplicate_pad_numbers_are_jumpers no)
		(fp_poly
			(pts
				(arc
					(start 0 -0.3556)
					(mid 0 0.3556)
					(end 0 -0.3556)
				)
			)
			(stroke
				(width 0)
				(type default)
			)
			(fill no)
			(layer "B.CrtYd")
		)
		(fp_poly
			(pts
				(arc
					(start 0 -0.6096)
					(mid 0 0.6096)
					(end 0 -0.6096)
				)
			)
			(stroke
				(width 0)
				(type default)
			)
			(fill no)
			(layer "B.Fab")
		)
		(pad "1" smd circle
			(at 0 0 90)
			(size 0.7112 0.7112)
			(layers "B.Cu" "B.Mask" "B.Paste")
			(net "LBI_DATA10")
		)
	)
	(footprint ""
		(layer "B.Cu")
		(at 228.6254 -43.997372 90)
		(property "Reference" "C573"
			(at 0 0 90)
			(layer "B.SilkS")
			(hide yes)
			(effects
				(font
					(size 1.27 1.27)
				)
				(justify mirror)
			)
		)
		(property "Value" "SCD1U16V1KX-1-GP"
			(at 2.8321 -1.7399 90)
			(unlocked yes)
			(layer "B.Fab")
			(hide yes)
			(effects
				(font
					(size 1.016 1.016)
					(thickness 0.1524)
				)
				(justify mirror)
			)
		)
		(property "Device Type" "C0201H13"
			(at 2.8321 -3.2639 90)
			(unlocked yes)
			(layer "B.Fab")
			(hide yes)
			(effects
				(font
					(size 1.016 1.016)
					(thickness 0.1524)
				)
				(justify mirror)
			)
		)
		(duplicate_pad_numbers_are_jumpers no)
		(fp_rect
			(start 0.2794 0.6477)
			(end -0.2794 -0.6477)
			(stroke
				(width 0)
				(type default)
			)
			(fill no)
			(layer "B.CrtYd")
		)
		(fp_rect
			(start 0.2794 0.6477)
			(end -0.2794 -0.6477)
			(stroke
				(width 0)
				(type default)
			)
			(fill no)
			(layer "B.Fab")
		)
		(pad "1" smd custom
			(at 0 -0.2794 270)
			(size 0.0762 0.0762)
			(layers "B.Cu" "B.Mask" "B.Paste")
			(net "DUT_AVD_PCIE")
			(options
				(clearance outline)
				(anchor circle)
			)
			(primitives
				(gr_poly
					(pts
						(arc
							(start 0.1524 0.127)
							(mid 0.137521 0.162921)
							(end 0.1016 0.1778)
						)
						(arc
							(start -0.1016 0.1778)
							(mid -0.137521 0.162921)
							(end -0.1524 0.127)
						)
						(arc
							(start -0.1524 -0.127)
							(mid -0.137521 -0.162921)
							(end -0.1016 -0.1778)
						)
						(arc
							(start 0.1016 -0.1778)
							(mid 0.137521 -0.162921)
							(end 0.1524 -0.127)
						)
					)
					(width 0)
					(fill yes)
				)
			)
		)
		(pad "2" smd custom
			(at 0 0.2794 270)
			(size 0.0762 0.0762)
			(layers "B.Cu" "B.Mask" "B.Paste")
			(net "GND")
			(options
				(clearance outline)
				(anchor circle)
			)
			(primitives
				(gr_poly
					(pts
						(arc
							(start 0.1524 0.127)
							(mid 0.137521 0.162921)
							(end 0.1016 0.1778)
						)
						(arc
							(start -0.1016 0.1778)
							(mid -0.137521 0.162921)
							(end -0.1524 0.127)
						)
						(arc
							(start -0.1524 -0.127)
							(mid -0.137521 -0.162921)
							(end -0.1016 -0.1778)
						)
						(arc
							(start 0.1016 -0.1778)
							(mid 0.137521 -0.162921)
							(end 0.1524 -0.127)
						)
					)
					(width 0)
					(fill yes)
				)
			)
		)
	)
	(footprint ""
		(layer "B.Cu")
		(at 242.599972 -35.999928 90)
		(property "Reference" "TP164"
			(at 0 0 90)
			(layer "B.SilkS")
			(hide yes)
			(effects
				(font
					(size 1.27 1.27)
				)
				(justify mirror)
			)
		)
		(property "Value" "TPAD28-2-GP"
			(at 0.0127 -1.6637 90)
			(unlocked yes)
			(layer "B.Fab")
			(hide yes)
			(effects
				(font
					(size 1.016 1.016)
					(thickness 0.1524)
				)
				(justify mirror)
			)
		)
		(property "Device Type" "TPAD28"
			(at 0.0127 -3.1877 90)
			(unlocked yes)
			(layer "B.Fab")
			(hide yes)
			(effects
				(font
					(size 1.016 1.016)
					(thickness 0.1524)
				)
				(justify mirror)
			)
		)
		(duplicate_pad_numbers_are_jumpers no)
		(fp_poly
			(pts
				(arc
					(start 0 0.3556)
					(mid 0 -0.3556)
					(end 0 0.3556)
				)
			)
			(stroke
				(width 0)
				(type default)
			)
			(fill no)
			(layer "B.CrtYd")
		)
		(fp_poly
			(pts
				(arc
					(start 0 0.6096)
					(mid 0 -0.6096)
					(end 0 0.6096)
				)
			)
			(stroke
				(width 0)
				(type default)
			)
			(fill no)
			(layer "B.Fab")
		)
		(pad "1" smd circle
			(at 0 0 270)
			(size 0.7112 0.7112)
			(layers "B.Cu" "B.Mask" "B.Paste")
			(net "LBI_BYTEN#")
		)
	)
	(footprint ""
		(layer "B.Cu")
		(at 243.59997 -32.999934)
		(property "Reference" "TP222"
			(at 0 0 0)
			(layer "B.SilkS")
			(hide yes)
			(effects
				(font
					(size 1.27 1.27)
				)
				(justify mirror)
			)
		)
		(property "Value" "TPAD28-2-GP"
			(at 0.0127 -1.6637 0)
			(unlocked yes)
			(layer "B.Fab")
			(hide yes)
			(effects
				(font
					(size 1.016 1.016)
					(thickness 0.1524)
				)
				(justify mirror)
			)
		)
		(property "Device Type" "TPAD28"
			(at 0.0127 -3.1877 0)
			(unlocked yes)
			(layer "B.Fab")
			(hide yes)
			(effects
				(font
					(size 1.016 1.016)
					(thickness 0.1524)
				)
				(justify mirror)
			)
		)
		(duplicate_pad_numbers_are_jumpers no)
		(fp_poly
			(pts
				(arc
					(start 0.3556 0)
					(mid -0.3556 0)
					(end 0.3556 0)
				)
			)
			(stroke
				(width 0)
				(type default)
			)
			(fill no)
			(layer "B.CrtYd")
		)
		(fp_poly
			(pts
				(arc
					(start 0.6096 0)
					(mid -0.6096 0)
					(end 0.6096 0)
				)
			)
			(stroke
				(width 0)
				(type default)
			)
			(fill no)
			(layer "B.Fab")
		)
		(pad "1" smd circle
			(at 0 0 180)
			(size 0.7112 0.7112)
			(layers "B.Cu" "B.Mask" "B.Paste")
			(net "LBI_DATA_3")
		)
	)
)
